# S9S_MB_2U (Grand Teton) — schematic netlist excerpt (pin names and nets, part order shuffled) for the footprints in the layout excerpt that follows; sources: Cadence DE-HDL packaged netlist, KiCad conversion of 03242023_DA0F0TMBIJ0_F0T_Motherboard_J_brd_V01_OCP.brd

R344  Q_RES  0 5% CHIP  pkg 0402LF  page 225 : A = H_CPU0_ERR2_LVC1_R_N ; B = H_CPU_ERR2_LVC1_R_N
C1930  Q_CAP  0.01UF 50V 10% X7R  pkg C0402  page 217 : A = P3V3_AUX_FPGA_VCCIO1 ; B = GND

(kicad_pcb
	(version 20260206)
	(generator "pcbnew")
	(generator_version "10.0")
	(general
		(thickness 1.6)
		(legacy_teardrops no)
	)
	(paper "A4")
	(title_block
		(title "03242023_DA0F0TMBIJ0_F0T_Motherboard_J_brd_V01_OCP.brd")
		(comment 1 "Grand Teton / footprints 5585-5586 of 6105")
	)
	(layers
		(0 "F.Cu" signal "TOP")
		(4 "In1.Cu" signal "GND")
		(6 "In2.Cu" signal "IN1")
		(8 "In3.Cu" signal "GND1")
		(10 "In4.Cu" signal "IN2")
		(12 "In5.Cu" signal "GND2")
		(14 "In6.Cu" signal "IN3")
		(16 "In7.Cu" signal "GND3")
		(18 "In8.Cu" signal "VCC")
		(20 "In9.Cu" signal "VCC1")
		(22 "In10.Cu" signal "GND4")
		(24 "In11.Cu" signal "IN4")
		(26 "In12.Cu" signal "GND5")
		(28 "In13.Cu" signal "IN5")
		(30 "In14.Cu" signal "GND6")
		(32 "In15.Cu" signal "IN6")
		(34 "In16.Cu" signal "GND7")
		(2 "B.Cu" signal "BOTTOM")
		(9 "F.Adhes" user "F.Adhesive")
		(11 "B.Adhes" user "B.Adhesive")
		(13 "F.Paste" user "Package Geometry/Pastemask Top")
		(15 "B.Paste" user "Package Geometry/Pastemask Bottom")
		(5 "F.SilkS" user "Ref Des/Silkscreen Top")
		(7 "B.SilkS" user "Ref Des/Silkscreen Bottom")
		(1 "F.Mask" user "Board Geometry/Soldermask Top")
		(3 "B.Mask" user "Board Geometry/Soldermask Bottom")
		(17 "Dwgs.User" user "User.Drawings")
		(19 "Cmts.User" user "User.Comments")
		(21 "Eco1.User" user "User.Eco1")
		(23 "Eco2.User" user "User.Eco2")
		(25 "Edge.Cuts" user "Board Geometry/Outline")
		(27 "Margin" user)
		(31 "F.CrtYd" user "Package Geometry/Place Bound Top")
		(29 "B.CrtYd" user "Package Geometry/Place Bound Bottom")
		(35 "F.Fab" user "Ref Des/Assembly Top")
		(33 "B.Fab" user "Ref Des/Assembly Bottom")
	)
	(footprint ""
		(layer "B.Cu")
		(at 177.355754 -115.775486 90)
		(property "Reference" "C1930"
			(at 0 0 90)
			(layer "B.SilkS")
			(hide yes)
			(effects
				(font
					(size 1.27 1.27)
				)
				(justify mirror)
			)
		)
		(property "Value" ""
			(at 0 0 90)
			(layer "B.Fab")
			(effects
				(font
					(size 1.27 1.27)
				)
				(justify mirror)
			)
		)
		(duplicate_pad_numbers_are_jumpers no)
		(fp_line
			(start 0.69215 -0.2921)
			(end -0.69215 -0.2921)
			(stroke
				(width 0.1524)
				(type default)
			)
			(layer "B.SilkS")
		)
		(fp_line
			(start -0.69215 -0.2921)
			(end -0.69215 0.2921)
			(stroke
				(width 0.1524)
				(type default)
			)
			(layer "B.SilkS")
		)
		(fp_line
			(start 0.69215 0.2921)
			(end 0.69215 -0.2921)
			(stroke
				(width 0.1524)
				(type default)
			)
			(layer "B.SilkS")
		)
		(fp_line
			(start -0.69215 0.2921)
			(end 0.69215 0.2921)
			(stroke
				(width 0.1524)
				(type default)
			)
			(layer "B.SilkS")
		)
		(fp_line
			(start 0.51435 -0.2794)
			(end -0.51435 -0.2794)
			(stroke
				(width 0.1)
				(type default)
			)
			(layer "B.Fab")
		)
		(fp_line
			(start -0.51435 -0.2794)
			(end -0.51435 0.2794)
			(stroke
				(width 0.1)
				(type default)
			)
			(layer "B.Fab")
		)
		(fp_line
			(start 0.51435 0.2794)
			(end 0.51435 -0.2794)
			(stroke
				(width 0.1)
				(type default)
			)
			(layer "B.Fab")
		)
		(fp_line
			(start -0.51435 0.2794)
			(end 0.51435 0.2794)
			(stroke
				(width 0.1)
				(type default)
			)
			(layer "B.Fab")
		)
		(pad "1" smd circle
			(at 0.40005 0 270)
			(size 0 0)
			(layers "B.Cu" "B.Mask" "B.Paste")
			(net "P3V3_AUX_FPGA_VCCIO1")
		)
		(pad "2" smd circle
			(at -0.40005 0 270)
			(size 0 0)
			(layers "B.Cu" "B.Mask" "B.Paste")
			(net "GND")
		)
		(zone
			(layer "B.Cu")
			(hatch none 0.5)
			(connect_pads
				(clearance 0)
			)
			(min_thickness 0.25)
			(keepout
				(tracks not_allowed)
				(vias allowed)
				(pads allowed)
				(copperpour not_allowed)
				(footprints allowed)
			)
			(placement
				(enabled no)
				(sheetname "")
			)
			(fill
				(thermal_gap 0.5)
				(thermal_bridge_width 0.5)
				(island_removal_mode 0)
			)
			(polygon
				(pts
					(xy 177.443384 -115.965986) (xy 177.50155 -115.874546) (xy 177.50155 -115.675156) (xy 177.443384 -115.584986)
					(xy 177.268124 -115.584986) (xy 177.209704 -115.675156) (xy 177.209704 -115.874546) (xy 177.26787 -115.965986)
				)
			)
		)
	)
	(footprint ""
		(layer "B.Cu")
		(at 317.56604 -193.53911 90)
		(property "Reference" "R344"
			(at 0 0 90)
			(layer "B.SilkS")
			(hide yes)
			(effects
				(font
					(size 1.27 1.27)
				)
				(justify mirror)
			)
		)
		(property "Value" ""
			(at 0 0 90)
			(layer "B.Fab")
			(effects
				(font
					(size 1.27 1.27)
				)
				(justify mirror)
			)
		)
		(duplicate_pad_numbers_are_jumpers no)
		(fp_line
			(start 0.7874 -0.4064)
			(end -0.7874 -0.4064)
			(stroke
				(width 0.1524)
				(type default)
			)
			(layer "B.SilkS")
		)
		(fp_line
			(start -0.7874 -0.4064)
			(end -0.7874 0.4064)
			(stroke
				(width 0.1524)
				(type default)
			)
			(layer "B.SilkS")
		)
		(fp_line
			(start 0.7874 0.4064)
			(end 0.7874 -0.4064)
			(stroke
				(width 0.1524)
				(type default)
			)
			(layer "B.SilkS")
		)
		(fp_line
			(start -0.7874 0.4064)
			(end 0.7874 0.4064)
			(stroke
				(width 0.1524)
				(type default)
			)
			(layer "B.SilkS")
		)
		(fp_line
			(start 0.67945 -0.305054)
			(end 0.12065 -0.305054)
			(stroke
				(width 0.1)
				(type default)
			)
			(layer "B.Fab")
		)
		(fp_line
			(start 0.12065 -0.305054)
			(end 0.12065 -0.2794)
			(stroke
				(width 0.1)
				(type default)
			)
			(layer "B.Fab")
		)
		(fp_line
			(start -0.12065 -0.3048)
			(end -0.67945 -0.3048)
			(stroke
				(width 0.1)
				(type default)
			)
			(layer "B.Fab")
		)
		(fp_line
			(start -0.67945 -0.3048)
			(end -0.67945 0.3048)
			(stroke
				(width 0.1)
				(type default)
			)
			(layer "B.Fab")
		)
		(fp_line
			(start 0.12065 -0.2794)
			(end -0.12065 -0.2794)
			(stroke
				(width 0.1)
				(type default)
			)
			(layer "B.Fab")
		)
		(fp_line
			(start -0.12065 -0.2794)
			(end -0.12065 -0.3048)
			(stroke
				(width 0.1)
				(type default)
			)
			(layer "B.Fab")
		)
		(fp_line
			(start 0.12065 0.2794)
			(end 0.12065 0.3048)
			(stroke
				(width 0.1)
				(type default)
			)
			(layer "B.Fab")
		)
		(fp_line
			(start -0.120396 0.2794)
			(end 0.12065 0.2794)
			(stroke
				(width 0.1)
				(type default)
			)
			(layer "B.Fab")
		)
		(fp_line
			(start 0.67945 0.3048)
			(end 0.67945 -0.305054)
			(stroke
				(width 0.1)
				(type default)
			)
			(layer "B.Fab")
		)
		(fp_line
			(start 0.12065 0.3048)
			(end 0.67945 0.3048)
			(stroke
				(width 0.1)
				(type default)
			)
			(layer "B.Fab")
		)
		(fp_line
			(start -0.120396 0.3048)
			(end -0.120396 0.2794)
			(stroke
				(width 0.1)
				(type default)
			)
			(layer "B.Fab")
		)
		(fp_line
			(start -0.67945 0.3048)
			(end -0.120396 0.3048)
			(stroke
				(width 0.1)
				(type default)
			)
			(layer "B.Fab")
		)
		(pad "1" smd circle
			(at 0.40005 0 270)
			(size 0 0)
			(layers "B.Cu" "B.Mask" "B.Paste")
			(net "H_CPU0_ERR2_LVC1_R_N")
		)
		(pad "2" smd circle
			(at -0.40005 0 270)
			(size 0 0)
			(layers "B.Cu" "B.Mask" "B.Paste")
			(net "H_CPU_ERR2_LVC1_R_N")
		)
	)
)
